(kicad_pcb
	(version 20260206)
	(generator "pcbnew")
	(generator_version "10.0")
	(general
		(thickness 1.6)
		(legacy_teardrops no)
	)
	(paper "A4")
	(title_block
		(title "03242023_DA0F0TMBIJ0_F0T_Motherboard_J_brd_V01_OCP.brd")
		(comment 1 "Grand Teton / footprints 3478-3482 of 6105")
	)
	(layers
		(0 "F.Cu" signal "TOP")
		(4 "In1.Cu" signal "GND")
		(6 "In2.Cu" signal "IN1")
		(8 "In3.Cu" signal "GND1")
		(10 "In4.Cu" signal "IN2")
		(12 "In5.Cu" signal "GND2")
		(14 "In6.Cu" signal "IN3")
		(16 "In7.Cu" signal "GND3")
		(18 "In8.Cu" signal "VCC")
		(20 "In9.Cu" signal "VCC1")
		(22 "In10.Cu" signal "GND4")
		(24 "In11.Cu" signal "IN4")
		(26 "In12.Cu" signal "GND5")
		(28 "In13.Cu" signal "IN5")
		(30 "In14.Cu" signal "GND6")
		(32 "In15.Cu" signal "IN6")
		(34 "In16.Cu" signal "GND7")
		(2 "B.Cu" signal "BOTTOM")
		(9 "F.Adhes" user "F.Adhesive")
		(11 "B.Adhes" user "B.Adhesive")
		(13 "F.Paste" user "Package Geometry/Pastemask Top")
		(15 "B.Paste" user "Package Geometry/Pastemask Bottom")
		(5 "F.SilkS" user "Ref Des/Silkscreen Top")
		(7 "B.SilkS" user "Ref Des/Silkscreen Bottom")
		(1 "F.Mask" user "Board Geometry/Soldermask Top")
		(3 "B.Mask" user "Board Geometry/Soldermask Bottom")
		(17 "Dwgs.User" user "User.Drawings")
		(19 "Cmts.User" user "User.Comments")
		(21 "Eco1.User" user "User.Eco1")
		(23 "Eco2.User" user "User.Eco2")
		(25 "Edge.Cuts" user "Board Geometry/Outline")
		(27 "Margin" user)
		(31 "F.CrtYd" user "Package Geometry/Place Bound Top")
		(29 "B.CrtYd" user "Package Geometry/Place Bound Bottom")
		(35 "F.Fab" user "Ref Des/Assembly Top")
		(33 "B.Fab" user "Ref Des/Assembly Bottom")
	)
	(footprint ""
		(layer "F.Cu")
		(at 382.875028 -206.024734)
		(property "Reference" "H21"
			(at 5.236972 -2.066544 0)
			(unlocked yes)
			(layer "F.SilkS")
			(effects
				(font
					(size 0.7874 0.5842)
					(thickness 0.1524)
				)
				(justify left)
			)
		)
		(property "Value" ""
			(at 0 0 0)
			(layer "F.Fab")
			(effects
				(font
					(size 1.27 1.27)
				)
			)
		)
		(duplicate_pad_numbers_are_jumpers no)
		(fp_arc
			(start -1.202944 -2.222754)
			(mid 1.293612 -2.171092)
			(end 2.5273 0)
			(stroke
				(width 0.1524)
				(type default)
			)
			(layer "F.SilkS")
		)
		(fp_arc
			(start 2.5273 0)
			(mid 0.497397 2.477827)
			(end -2.331466 0.97536)
			(stroke
				(width 0.1524)
				(type default)
			)
			(layer "F.SilkS")
		)
		(fp_circle
			(center 0 0)
			(end 2.5273 0)
			(stroke
				(width 0.1524)
				(type default)
			)
			(fill no)
			(layer "B.SilkS")
		)
		(fp_circle
			(center 0 0)
			(end 2.5273 0)
			(stroke
				(width 0.1)
				(type default)
			)
			(fill no)
			(layer "B.Fab")
		)
		(fp_circle
			(center 0 0)
			(end 2.5273 0)
			(stroke
				(width 0.1)
				(type default)
			)
			(fill no)
			(layer "F.Fab")
		)
		(pad "" np_thru_hole circle
			(at 0 0)
			(size 3.429 3.429)
			(drill 3.429)
			(layers "*.Cu" "*.Mask")
			(clearance 0.381)
			(thermal_gap 0.381)
		)
	)
	(footprint ""
		(layer "F.Cu")
		(at 173.899322 -28.03779 -90)
		(property "Reference" "PR4011"
			(at 0 0 270)
			(layer "F.SilkS")
			(hide yes)
			(effects
				(font
					(size 1.27 1.27)
				)
			)
		)
		(property "Value" ""
			(at 0 0 270)
			(layer "F.Fab")
			(effects
				(font
					(size 1.27 1.27)
				)
			)
		)
		(duplicate_pad_numbers_are_jumpers no)
		(fp_line
			(start -0.7874 0.4064)
			(end -0.7874 -0.4064)
			(stroke
				(width 0.1524)
				(type default)
			)
			(layer "F.SilkS")
		)
		(fp_line
			(start 0.7874 0.4064)
			(end -0.7874 0.4064)
			(stroke
				(width 0.1524)
				(type default)
			)
			(layer "F.SilkS")
		)
		(fp_line
			(start -0.7874 -0.4064)
			(end 0.7874 -0.4064)
			(stroke
				(width 0.1524)
				(type default)
			)
			(layer "F.SilkS")
		)
		(fp_line
			(start 0.7874 -0.4064)
			(end 0.7874 0.4064)
			(stroke
				(width 0.1524)
				(type default)
			)
			(layer "F.SilkS")
		)
		(fp_line
			(start -0.67945 0.3048)
			(end -0.67945 -0.305054)
			(stroke
				(width 0.1)
				(type default)
			)
			(layer "F.Fab")
		)
		(fp_line
			(start -0.12065 0.3048)
			(end -0.67945 0.3048)
			(stroke
				(width 0.1)
				(type default)
			)
			(layer "F.Fab")
		)
		(fp_line
			(start 0.120396 0.3048)
			(end 0.120396 0.2794)
			(stroke
				(width 0.1)
				(type default)
			)
			(layer "F.Fab")
		)
		(fp_line
			(start 0.67945 0.3048)
			(end 0.120396 0.3048)
			(stroke
				(width 0.1)
				(type default)
			)
			(layer "F.Fab")
		)
		(fp_line
			(start -0.12065 0.2794)
			(end -0.12065 0.3048)
			(stroke
				(width 0.1)
				(type default)
			)
			(layer "F.Fab")
		)
		(fp_line
			(start 0.120396 0.2794)
			(end -0.12065 0.2794)
			(stroke
				(width 0.1)
				(type default)
			)
			(layer "F.Fab")
		)
		(fp_line
			(start -0.12065 -0.2794)
			(end 0.12065 -0.2794)
			(stroke
				(width 0.1)
				(type default)
			)
			(layer "F.Fab")
		)
		(fp_line
			(start 0.12065 -0.2794)
			(end 0.12065 -0.3048)
			(stroke
				(width 0.1)
				(type default)
			)
			(layer "F.Fab")
		)
		(fp_line
			(start 0.12065 -0.3048)
			(end 0.67945 -0.3048)
			(stroke
				(width 0.1)
				(type default)
			)
			(layer "F.Fab")
		)
		(fp_line
			(start 0.67945 -0.3048)
			(end 0.67945 0.3048)
			(stroke
				(width 0.1)
				(type default)
			)
			(layer "F.Fab")
		)
		(fp_line
			(start -0.67945 -0.305054)
			(end -0.12065 -0.305054)
			(stroke
				(width 0.1)
				(type default)
			)
			(layer "F.Fab")
		)
		(fp_line
			(start -0.12065 -0.305054)
			(end -0.12065 -0.2794)
			(stroke
				(width 0.1)
				(type default)
			)
			(layer "F.Fab")
		)
		(pad "1" smd circle
			(at -0.40005 0 270)
			(size 0 0)
			(layers "F.Cu" "F.Mask" "F.Paste")
			(net "P12V_SCM_OV_FB")
		)
		(pad "2" smd circle
			(at 0.40005 0 270)
			(size 0 0)
			(layers "F.Cu" "F.Mask" "F.Paste")
			(net "GND")
		)
	)
	(footprint ""
		(layer "F.Cu")
		(at 492.12627 -468.00135)
		(property "Reference" "U1_DC"
			(at -0.90551 1.402842 0)
			(unlocked yes)
			(layer "F.SilkS")
			(effects
				(font
					(size 0.7874 0.5842)
					(thickness 0.1524)
				)
				(justify left)
			)
		)
		(property "Value" ""
			(at 0 0 0)
			(layer "F.Fab")
			(effects
				(font
					(size 1.27 1.27)
				)
			)
		)
		(duplicate_pad_numbers_are_jumpers no)
		(pad "1" smd circle
			(at 0 0)
			(size 0.762 0.762)
			(layers "F.Cu" "F.Mask" "F.Paste")
			(net "Net_8486")
		)
	)
	(footprint ""
		(layer "F.Cu")
		(at 354.270818 -245.634002 -90)
		(property "Reference" "C987"
			(at 0 0 270)
			(layer "F.SilkS")
			(hide yes)
			(effects
				(font
					(size 1.27 1.27)
				)
			)
		)
		(property "Value" ""
			(at 0 0 270)
			(layer "F.Fab")
			(effects
				(font
					(size 1.27 1.27)
				)
			)
		)
		(duplicate_pad_numbers_are_jumpers no)
		(fp_line
			(start -0.7874 0.4064)
			(end -0.7874 -0.4064)
			(stroke
				(width 0.1524)
				(type default)
			)
			(layer "F.SilkS")
		)
		(fp_line
			(start 0.7874 0.4064)
			(end -0.7874 0.4064)
			(stroke
				(width 0.1524)
				(type default)
			)
			(layer "F.SilkS")
		)
		(fp_line
			(start -0.7874 -0.4064)
			(end 0.7874 -0.4064)
			(stroke
				(width 0.1524)
				(type default)
			)
			(layer "F.SilkS")
		)
		(fp_line
			(start 0.7874 -0.4064)
			(end 0.7874 0.4064)
			(stroke
				(width 0.1524)
				(type default)
			)
			(layer "F.SilkS")
		)
		(fp_line
			(start -0.67945 0.3048)
			(end -0.67945 -0.305054)
			(stroke
				(width 0.1)
				(type default)
			)
			(layer "F.Fab")
		)
		(fp_line
			(start -0.12065 0.3048)
			(end -0.67945 0.3048)
			(stroke
				(width 0.1)
				(type default)
			)
			(layer "F.Fab")
		)
		(fp_line
			(start 0.120396 0.3048)
			(end 0.120396 0.2794)
			(stroke
				(width 0.1)
				(type default)
			)
			(layer "F.Fab")
		)
		(fp_line
			(start 0.67945 0.3048)
			(end 0.120396 0.3048)
			(stroke
				(width 0.1)
				(type default)
			)
			(layer "F.Fab")
		)
		(fp_line
			(start -0.12065 0.2794)
			(end -0.12065 0.3048)
			(stroke
				(width 0.1)
				(type default)
			)
			(layer "F.Fab")
		)
		(fp_line
			(start 0.120396 0.2794)
			(end -0.12065 0.2794)
			(stroke
				(width 0.1)
				(type default)
			)
			(layer "F.Fab")
		)
		(fp_line
			(start -0.12065 -0.2794)
			(end 0.12065 -0.2794)
			(stroke
				(width 0.1)
				(type default)
			)
			(layer "F.Fab")
		)
		(fp_line
			(start 0.12065 -0.2794)
			(end 0.12065 -0.3048)
			(stroke
				(width 0.1)
				(type default)
			)
			(layer "F.Fab")
		)
		(fp_line
			(start 0.12065 -0.3048)
			(end 0.67945 -0.3048)
			(stroke
				(width 0.1)
				(type default)
			)
			(layer "F.Fab")
		)
		(fp_line
			(start 0.67945 -0.3048)
			(end 0.67945 0.3048)
			(stroke
				(width 0.1)
				(type default)
			)
			(layer "F.Fab")
		)
		(fp_line
			(start -0.67945 -0.305054)
			(end -0.12065 -0.305054)
			(stroke
				(width 0.1)
				(type default)
			)
			(layer "F.Fab")
		)
		(fp_line
			(start -0.12065 -0.305054)
			(end -0.12065 -0.2794)
			(stroke
				(width 0.1)
				(type default)
			)
			(layer "F.Fab")
		)
		(pad "1" smd circle
			(at -0.40005 0 270)
			(size 0 0)
			(layers "F.Cu" "F.Mask" "F.Paste")
			(net "PVCCIN_CPU0")
		)
		(pad "2" smd circle
			(at 0.40005 0 270)
			(size 0 0)
			(layers "F.Cu" "F.Mask" "F.Paste")
			(net "GND")
		)
	)
	(footprint ""
		(layer "F.Cu")
		(at 263.517126 -93.457776)
		(property "Reference" "R519"
			(at 0 0 0)
			(layer "F.SilkS")
			(hide yes)
			(effects
				(font
					(size 1.27 1.27)
				)
			)
		)
		(property "Value" ""
			(at 0 0 0)
			(layer "F.Fab")
			(effects
				(font
					(size 1.27 1.27)
				)
			)
		)
		(duplicate_pad_numbers_are_jumpers no)
		(fp_line
			(start -1.2954 -0.5842)
			(end 1.2954 -0.5842)
			(stroke
				(width 0.1524)
				(type default)
			)
			(layer "F.SilkS")
		)
		(fp_line
			(start -1.2954 0.5842)
			(end -1.2954 -0.5842)
			(stroke
				(width 0.1524)
				(type default)
			)
			(layer "F.SilkS")
		)
		(fp_line
			(start 1.2954 -0.5842)
			(end 1.2954 0.5842)
			(stroke
				(width 0.1524)
				(type default)
			)
			(layer "F.SilkS")
		)
		(fp_line
			(start 1.2954 0.5842)
			(end -1.2954 0.5842)
			(stroke
				(width 0.1524)
				(type default)
			)
			(layer "F.SilkS")
		)
		(fp_line
			(start -1.1938 -0.406654)
			(end -0.8636 -0.406654)
			(stroke
				(width 0.1)
				(type default)
			)
			(layer "F.Fab")
		)
		(fp_line
			(start -1.1938 0.4064)
			(end -1.1938 -0.406654)
			(stroke
				(width 0.1)
				(type default)
			)
			(layer "F.Fab")
		)
		(fp_line
			(start -0.8636 -0.4572)
			(end 0.8636 -0.4572)
			(stroke
				(width 0.1)
				(type default)
			)
			(layer "F.Fab")
		)
		(fp_line
			(start -0.8636 -0.406654)
			(end -0.8636 -0.4572)
			(stroke
				(width 0.1)
				(type default)
			)
			(layer "F.Fab")
		)
		(fp_line
			(start -0.8636 0.4064)
			(end -1.1938 0.4064)
			(stroke
				(width 0.1)
				(type default)
			)
			(layer "F.Fab")
		)
		(fp_line
			(start -0.8636 0.4318)
			(end -0.8636 0.4064)
			(stroke
				(width 0.1)
				(type default)
			)
			(layer "F.Fab")
		)
		(fp_line
			(start -0.8636 0.4572)
			(end -0.8636 0.4318)
			(stroke
				(width 0.1)
				(type default)
			)
			(layer "F.Fab")
		)
		(fp_line
			(start 0.8636 -0.4572)
			(end 0.8636 -0.406654)
			(stroke
				(width 0.1)
				(type default)
			)
			(layer "F.Fab")
		)
		(fp_line
			(start 0.8636 -0.406654)
			(end 1.1938 -0.406654)
			(stroke
				(width 0.1)
				(type default)
			)
			(layer "F.Fab")
		)
		(fp_line
			(start 0.8636 0.4064)
			(end 0.8636 0.4572)
			(stroke
				(width 0.1)
				(type default)
			)
			(layer "F.Fab")
		)
		(fp_line
			(start 0.8636 0.4572)
			(end -0.8636 0.4572)
			(stroke
				(width 0.1)
				(type default)
			)
			(layer "F.Fab")
		)
		(fp_line
			(start 1.1938 -0.406654)
			(end 1.1938 0.4064)
			(stroke
				(width 0.1)
				(type default)
			)
			(layer "F.Fab")
		)
		(fp_line
			(start 1.1938 0.4064)
			(end 0.8636 0.4064)
			(stroke
				(width 0.1)
				(type default)
			)
			(layer "F.Fab")
		)
		(pad "1" smd rect
			(at -0.7366 0 270)
			(size 0.7112 0.8128)
			(layers "F.Cu" "F.Mask" "F.Paste")
			(net "P3V3_AUX_CLK_GEN_VDD_CK440")
		)
		(pad "2" smd rect
			(at 0.7366 0 270)
			(size 0.7112 0.8128)
			(layers "F.Cu" "F.Mask" "F.Paste")
			(net "P3V3_AUX_CLK_GEN_VDDA100M_CK440")
		)
	)
)
